(kicad_pcb
	(version 20260206)
	(generator "pcbnew")
	(generator_version "10.0")
	(general
		(thickness 1.6)
		(legacy_teardrops no)
	)
	(paper "A4")
	(title_block
		(title "timecard-production-celestica-r4006 — R4006-B0001-02_R01.brd")
		(comment 1 "Time Appliance Project (Time Card) / footprints 264-268 of 1113")
	)
	(layers
		(0 "F.Cu" signal "TOP")
		(4 "In1.Cu" signal "L02_GND1")
		(6 "In2.Cu" signal "L03_SIG1")
		(8 "In3.Cu" signal "L04_GND2")
		(10 "In4.Cu" signal "L05_VCC1")
		(12 "In5.Cu" signal "L06_VCC2")
		(14 "In6.Cu" signal "L07_GND3")
		(16 "In7.Cu" signal "L08_SIG2")
		(18 "In8.Cu" signal "L09_GND4")
		(2 "B.Cu" signal "BOTTOM")
		(9 "F.Adhes" user "F.Adhesive")
		(11 "B.Adhes" user "B.Adhesive")
		(13 "F.Paste" user "Package Geometry/Pastemask Top")
		(15 "B.Paste" user "Package Geometry/Pastemask Bottom")
		(5 "F.SilkS" user "Ref Des/Silkscreen Top")
		(7 "B.SilkS" user "Ref Des/Silkscreen Bottom")
		(1 "F.Mask" user "Board Geometry/Soldermask Top")
		(3 "B.Mask" user "Board Geometry/Soldermask Bottom")
		(17 "Dwgs.User" user "User.Drawings")
		(19 "Cmts.User" user "User.Comments")
		(21 "Eco1.User" user "User.Eco1")
		(23 "Eco2.User" user "User.Eco2")
		(25 "Edge.Cuts" user "Board Geometry/Outline")
		(27 "Margin" user)
		(31 "F.CrtYd" user "Package Geometry/Place Bound Top")
		(29 "B.CrtYd" user "Package Geometry/Place Bound Bottom")
		(35 "F.Fab" user "Ref Des/Assembly Top")
		(33 "B.Fab" user "Ref Des/Assembly Bottom")
	)
	(footprint ""
		(layer "F.Cu")
		(at 115.443 -76.073 180)
		(property "Reference" "R143"
			(at -3.429 0.46863 0)
			(unlocked yes)
			(layer "F.SilkS")
			(effects
				(font
					(size 0.7874 0.5842)
					(thickness 0.1524)
				)
			)
		)
		(property "Value" "VAL*"
			(at 0.02032 2.13233 180)
			(unlocked yes)
			(layer "F.Fab")
			(hide yes)
			(effects
				(font
					(size 0.7874 0.5842)
					(thickness 0.1524)
				)
			)
		)
		(property "Device Type" "RESISTOR-G155-133R0-01,33OHM,1%"
			(at 0.008382 1.210564 180)
			(unlocked yes)
			(layer "F.Fab")
			(hide yes)
			(effects
				(font
					(size 0.7874 0.5842)
					(thickness 0.1524)
				)
			)
		)
		(property "User Part Number" "PARTNUM*"
			(at 0.02032 4.024884 180)
			(unlocked yes)
			(layer "Cmts.User")
			(hide yes)
			(effects
				(font
					(size 0.7874 0.5842)
					(thickness 0.1524)
				)
			)
		)
		(property "Tolerance" "TOL*"
			(at 0.044704 3.05435 180)
			(unlocked yes)
			(layer "Cmts.User")
			(hide yes)
			(effects
				(font
					(size 0.7874 0.5842)
					(thickness 0.1524)
				)
			)
		)
		(duplicate_pad_numbers_are_jumpers no)
		(fp_line
			(start 1.143 0.5588)
			(end 1.143 -0.5588)
			(stroke
				(width 0.1)
				(type default)
			)
			(layer "F.SilkS")
		)
		(fp_line
			(start 1.143 -0.5588)
			(end -1.143 -0.5588)
			(stroke
				(width 0.1)
				(type default)
			)
			(layer "F.SilkS")
		)
		(fp_line
			(start -1.143 0.5588)
			(end 1.143 0.5588)
			(stroke
				(width 0.1)
				(type default)
			)
			(layer "F.SilkS")
		)
		(fp_line
			(start -1.143 -0.5588)
			(end -1.143 0.5588)
			(stroke
				(width 0.1)
				(type default)
			)
			(layer "F.SilkS")
		)
		(fp_rect
			(start 1.143 0.5588)
			(end -1.143 -0.5588)
			(stroke
				(width 0)
				(type default)
			)
			(fill no)
			(layer "F.CrtYd")
		)
		(fp_line
			(start 0.508 0.3048)
			(end 0.508 -0.3048)
			(stroke
				(width 0.1)
				(type default)
			)
			(layer "F.Fab")
		)
		(fp_line
			(start 0.508 -0.3048)
			(end -0.508 -0.3048)
			(stroke
				(width 0.1)
				(type default)
			)
			(layer "F.Fab")
		)
		(fp_line
			(start -0.508 0.3048)
			(end 0.508 0.3048)
			(stroke
				(width 0.1)
				(type default)
			)
			(layer "F.Fab")
		)
		(fp_line
			(start -0.508 -0.3048)
			(end -0.508 0.3048)
			(stroke
				(width 0.1)
				(type default)
			)
			(layer "F.Fab")
		)
		(pad "1" smd rect
			(at -0.5334 0 180)
			(size 0.7112 0.6096)
			(layers "F.Cu" "F.Mask" "F.Paste")
			(net "FPGA_CFG_INIT_N")
		)
		(pad "2" smd rect
			(at 0.5334 0 180)
			(size 0.7112 0.6096)
			(layers "F.Cu" "F.Mask" "F.Paste")
			(net "UNNAMED_515_NCP45560IMNTWGHDFN1")
		)
		(zone
			(layer "F.Cu")
			(hatch none 0.5)
			(connect_pads
				(clearance 0)
			)
			(min_thickness 0.25)
			(keepout
				(tracks allowed)
				(vias not_allowed)
				(pads allowed)
				(copperpour not_allowed)
				(footprints allowed)
			)
			(placement
				(enabled no)
				(sheetname "")
			)
			(fill
				(thermal_gap 0.5)
				(thermal_bridge_width 0.5)
				(island_removal_mode 0)
			)
			(polygon
				(pts
					(xy 115.3668 -76.3778) (xy 115.3668 -75.7682) (xy 115.5192 -75.7682) (xy 115.5192 -76.3778)
				)
			)
		)
	)
	(footprint ""
		(layer "F.Cu")
		(at 66.802 -123.698)
		(property "Reference" "SP38"
			(at 0 0 0)
			(layer "F.SilkS")
			(hide yes)
			(effects
				(font
					(size 1.27 1.27)
				)
			)
		)
		(property "Value" ""
			(at 0 0 0)
			(layer "F.Fab")
			(effects
				(font
					(size 1.27 1.27)
				)
			)
		)
		(duplicate_pad_numbers_are_jumpers no)
	)
	(footprint ""
		(layer "F.Cu")
		(at 100.2538 -68.072 180)
		(property "Reference" "R178"
			(at -2.8702 0.08763 0)
			(unlocked yes)
			(layer "F.SilkS")
			(effects
				(font
					(size 0.7874 0.5842)
					(thickness 0.1524)
				)
			)
		)
		(property "Value" "VAL*"
			(at 0.02032 2.13233 180)
			(unlocked yes)
			(layer "F.Fab")
			(hide yes)
			(effects
				(font
					(size 0.7874 0.5842)
					(thickness 0.1524)
				)
			)
		)
		(property "Tolerance" "TOL*"
			(at 0.044704 3.05435 180)
			(unlocked yes)
			(layer "Cmts.User")
			(hide yes)
			(effects
				(font
					(size 0.7874 0.5842)
					(thickness 0.1524)
				)
			)
		)
		(property "User Part Number" "PARTNUM*"
			(at 0.02032 4.024884 180)
			(unlocked yes)
			(layer "Cmts.User")
			(hide yes)
			(effects
				(font
					(size 0.7874 0.5842)
					(thickness 0.1524)
				)
			)
		)
		(property "Device Type" "RESISTOR-G155-14701-01,4.7KOHMA"
			(at 0.008382 1.210564 180)
			(unlocked yes)
			(layer "F.Fab")
			(hide yes)
			(effects
				(font
					(size 0.7874 0.5842)
					(thickness 0.1524)
				)
			)
		)
		(duplicate_pad_numbers_are_jumpers no)
		(fp_line
			(start 1.143 0.5588)
			(end 1.143 -0.5588)
			(stroke
				(width 0.1)
				(type default)
			)
			(layer "F.SilkS")
		)
		(fp_line
			(start 1.143 -0.5588)
			(end -1.143 -0.5588)
			(stroke
				(width 0.1)
				(type default)
			)
			(layer "F.SilkS")
		)
		(fp_line
			(start -1.143 0.5588)
			(end 1.143 0.5588)
			(stroke
				(width 0.1)
				(type default)
			)
			(layer "F.SilkS")
		)
		(fp_line
			(start -1.143 -0.5588)
			(end -1.143 0.5588)
			(stroke
				(width 0.1)
				(type default)
			)
			(layer "F.SilkS")
		)
		(fp_rect
			(start 1.143 -0.5588)
			(end -1.143 0.5588)
			(stroke
				(width 0)
				(type default)
			)
			(fill no)
			(layer "F.CrtYd")
		)
		(fp_line
			(start 0.508 0.3048)
			(end 0.508 -0.3048)
			(stroke
				(width 0.1)
				(type default)
			)
			(layer "F.Fab")
		)
		(fp_line
			(start 0.508 -0.3048)
			(end -0.508 -0.3048)
			(stroke
				(width 0.1)
				(type default)
			)
			(layer "F.Fab")
		)
		(fp_line
			(start -0.508 0.3048)
			(end 0.508 0.3048)
			(stroke
				(width 0.1)
				(type default)
			)
			(layer "F.Fab")
		)
		(fp_line
			(start -0.508 -0.3048)
			(end -0.508 0.3048)
			(stroke
				(width 0.1)
				(type default)
			)
			(layer "F.Fab")
		)
		(pad "1" smd rect
			(at -0.5334 0 180)
			(size 0.7112 0.6096)
			(layers "F.Cu" "F.Mask" "F.Paste")
			(net "XP3R3V")
		)
		(pad "2" smd rect
			(at 0.5334 0 180)
			(size 0.7112 0.6096)
			(layers "F.Cu" "F.Mask" "F.Paste")
			(net "XP1R2V_PG_R")
		)
		(zone
			(layer "F.Cu")
			(hatch none 0.5)
			(connect_pads
				(clearance 0)
			)
			(min_thickness 0.25)
			(keepout
				(tracks allowed)
				(vias not_allowed)
				(pads allowed)
				(copperpour not_allowed)
				(footprints allowed)
			)
			(placement
				(enabled no)
				(sheetname "")
			)
			(fill
				(thermal_gap 0.5)
				(thermal_bridge_width 0.5)
				(island_removal_mode 0)
			)
			(polygon
				(pts
					(xy 100.1776 -67.7672) (xy 100.33 -67.7672) (xy 100.33 -68.3768) (xy 100.1776 -68.3768)
				)
			)
		)
	)
	(footprint ""
		(layer "F.Cu")
		(at 1.500124 -82.600038 90)
		(property "Reference" "DS18"
			(at -4.241038 0.698246 90)
			(unlocked yes)
			(layer "F.SilkS")
			(effects
				(font
					(size 0.7874 0.5842)
					(thickness 0.1524)
				)
			)
		)
		(property "Value" ""
			(at 0 0 90)
			(layer "F.Fab")
			(effects
				(font
					(size 1.27 1.27)
				)
			)
		)
		(property "User Part Number" "PARTNUM*"
			(at 0.015494 4.486402 90)
			(unlocked yes)
			(layer "Cmts.User")
			(hide yes)
			(effects
				(font
					(size 0.7874 0.5842)
					(thickness 0.1524)
				)
			)
		)
		(property "Device Type" "LED_4P_V14-G170-10189-01"
			(at 0.015494 3.292602 90)
			(unlocked yes)
			(layer "F.Fab")
			(hide yes)
			(effects
				(font
					(size 0.7874 0.5842)
					(thickness 0.1524)
				)
			)
		)
		(duplicate_pad_numbers_are_jumpers no)
		(fp_line
			(start 1.378966 -0.829056)
			(end -1.378966 -0.829056)
			(stroke
				(width 0.1)
				(type default)
			)
			(layer "F.SilkS")
		)
		(fp_line
			(start -1.378966 -0.829056)
			(end -1.378966 -0.452628)
			(stroke
				(width 0.1)
				(type default)
			)
			(layer "F.SilkS")
		)
		(fp_line
			(start 1.998218 -0.452628)
			(end 1.378966 -0.452628)
			(stroke
				(width 0.1)
				(type default)
			)
			(layer "F.SilkS")
		)
		(fp_line
			(start 1.378966 -0.452628)
			(end 1.378966 -0.829056)
			(stroke
				(width 0.1)
				(type default)
			)
			(layer "F.SilkS")
		)
		(fp_line
			(start -1.378966 -0.452628)
			(end -1.998218 -0.452628)
			(stroke
				(width 0.1)
				(type default)
			)
			(layer "F.SilkS")
		)
		(fp_line
			(start -1.998218 -0.452628)
			(end -1.998218 1.103884)
			(stroke
				(width 0.1)
				(type default)
			)
			(layer "F.SilkS")
		)
		(fp_line
			(start 1.998218 1.103884)
			(end 1.998218 -0.452628)
			(stroke
				(width 0.1)
				(type default)
			)
			(layer "F.SilkS")
		)
		(fp_line
			(start -1.998218 1.103884)
			(end 1.998218 1.103884)
			(stroke
				(width 0.1)
				(type default)
			)
			(layer "F.SilkS")
		)
		(fp_poly
			(pts
				(xy 0.918464 -1.698498) (xy 1.223264 -1.46939) (xy 0.994664 -1.46939) (xy 0.994664 -1.24079) (xy 0.842264 -1.24079)
				(xy 0.842264 -1.46939) (xy 0.613664 -1.46939)
			)
			(stroke
				(width 0)
				(type default)
			)
			(fill yes)
			(layer "F.SilkS")
		)
		(fp_poly
			(pts
				(xy -0.73406 -1.677416) (xy -0.42926 -1.448308) (xy -0.65786 -1.448308) (xy -0.65786 -1.219708)
				(xy -0.81026 -1.219708) (xy -0.81026 -1.448308) (xy -1.03886 -1.448308)
			)
			(stroke
				(width 0)
				(type default)
			)
			(fill yes)
			(layer "F.SilkS")
		)
		(fp_poly
			(pts
				(xy -2.252218 1.357884) (xy -2.252218 -0.706628) (xy -1.632966 -0.706628) (xy -1.632966 -1.083056)
				(xy 1.632966 -1.083056) (xy 1.632966 -0.706628) (xy 2.252218 -0.706628) (xy 2.252218 1.357884)
			)
			(stroke
				(width 0)
				(type default)
			)
			(fill no)
			(layer "F.CrtYd")
		)
		(fp_line
			(start 1.124966 -0.575056)
			(end -1.124966 -0.575056)
			(stroke
				(width 0.1)
				(type default)
			)
			(layer "F.Fab")
		)
		(fp_line
			(start -1.124966 -0.575056)
			(end -1.124966 -0.075184)
			(stroke
				(width 0.1)
				(type default)
			)
			(layer "F.Fab")
		)
		(fp_line
			(start 1.325118 -0.075184)
			(end 1.124966 -0.075184)
			(stroke
				(width 0.1)
				(type default)
			)
			(layer "F.Fab")
		)
		(fp_line
			(start 1.124966 -0.075184)
			(end 1.124966 -0.575056)
			(stroke
				(width 0.1)
				(type default)
			)
			(layer "F.Fab")
		)
		(fp_line
			(start -1.124966 -0.075184)
			(end -1.325118 -0.075184)
			(stroke
				(width 0.1)
				(type default)
			)
			(layer "F.Fab")
		)
		(fp_line
			(start -1.325118 -0.075184)
			(end -1.325118 0.574802)
			(stroke
				(width 0.1)
				(type default)
			)
			(layer "F.Fab")
		)
		(fp_line
			(start 1.325118 0.574802)
			(end 1.325118 -0.075184)
			(stroke
				(width 0.1)
				(type default)
			)
			(layer "F.Fab")
		)
		(fp_line
			(start -1.325118 0.574802)
			(end 1.325118 0.574802)
			(stroke
				(width 0.1)
				(type default)
			)
			(layer "F.Fab")
		)
		(fp_poly
			(pts
				(xy 0.918464 -1.698498) (xy 1.223264 -1.46939) (xy 0.994664 -1.46939) (xy 0.994664 -1.24079) (xy 0.842264 -1.24079)
				(xy 0.842264 -1.46939) (xy 0.613664 -1.46939)
			)
			(stroke
				(width 0)
				(type default)
			)
			(fill yes)
			(layer "F.Fab")
		)
		(fp_poly
			(pts
				(xy -0.73406 -1.677416) (xy -0.42926 -1.448308) (xy -0.65786 -1.448308) (xy -0.65786 -1.219708)
				(xy -0.81026 -1.219708) (xy -0.81026 -1.448308) (xy -1.03886 -1.448308)
			)
			(stroke
				(width 0)
				(type default)
			)
			(fill yes)
			(layer "F.Fab")
		)
		(fp_text user "1"
			(at -2.37617 0.445516 90)
			(unlocked yes)
			(layer "F.SilkS")
			(effects
				(font
					(size 0.635 0.4064)
					(thickness 0.1524)
				)
			)
		)
		(fp_text user "4"
			(at 0.350012 1.420876 0)
			(unlocked yes)
			(layer "F.SilkS")
			(effects
				(font
					(size 0.635 0.4064)
					(thickness 0.1524)
				)
			)
		)
		(fp_text user "2"
			(at -1.681988 1.420876 0)
			(unlocked yes)
			(layer "F.SilkS")
			(effects
				(font
					(size 0.635 0.4064)
					(thickness 0.1524)
				)
			)
		)
		(fp_text user "3"
			(at -0.030988 2.182876 0)
			(unlocked yes)
			(layer "F.SilkS")
			(effects
				(font
					(size 0.635 0.4064)
					(thickness 0.1524)
				)
			)
		)
		(fp_text user "1"
			(at -2.375916 0.376682 90)
			(unlocked yes)
			(layer "F.Fab")
			(effects
				(font
					(size 0.7874 0.5842)
					(thickness 0.1524)
				)
			)
		)
		(fp_text user "4"
			(at 1.727962 0.952246 90)
			(unlocked yes)
			(layer "F.Fab")
			(effects
				(font
					(size 0.7874 0.5842)
					(thickness 0.1524)
				)
			)
		)
		(fp_text user "3"
			(at 0.4953 1.283208 90)
			(unlocked yes)
			(layer "F.Fab")
			(effects
				(font
					(size 0.7874 0.5842)
					(thickness 0.1524)
				)
			)
		)
		(fp_text user "2"
			(at -0.526542 1.306576 90)
			(unlocked yes)
			(layer "F.Fab")
			(effects
				(font
					(size 0.7874 0.5842)
					(thickness 0.1524)
				)
			)
		)
		(pad "1" smd rect
			(at -1.325118 0.245872 90)
			(size 0.8382 0.889)
			(layers "F.Cu" "F.Mask" "F.Paste")
			(net "UNNAMED_14_LED4PV14_I269_1")
		)
		(pad "2" smd rect
			(at -0.424942 0.595884 90)
			(size 0.4572 0.508)
			(layers "F.Cu" "F.Mask" "F.Paste")
			(net "XP3R3V_FPGA")
		)
		(pad "3" smd rect
			(at 0.424942 0.595884 90)
			(size 0.4572 0.508)
			(layers "F.Cu" "F.Mask" "F.Paste")
			(net "UNNAMED_14_LED4PV14_I269_3")
		)
		(pad "4" smd rect
			(at 1.325118 0.245872 90)
			(size 0.8382 0.889)
			(layers "F.Cu" "F.Mask" "F.Paste")
			(net "UNNAMED_14_LED4PV14_I269_4")
		)
	)
	(footprint ""
		(layer "F.Cu")
		(at 137.414 -24.384)
		(property "Reference" "TP46"
			(at -1.0922 -1.61163 0)
			(unlocked yes)
			(layer "F.SilkS")
			(effects
				(font
					(size 0.7874 0.5842)
					(thickness 0.1524)
				)
				(justify left)
			)
		)
		(property "Value" ""
			(at 0 0 0)
			(layer "F.Fab")
			(effects
				(font
					(size 1.27 1.27)
				)
			)
		)
		(property "Device Type" "TP_PIONT-TP010CT020B030_PTH-TPA"
			(at -1.341882 0.996696 0)
			(unlocked yes)
			(layer "F.Fab")
			(hide yes)
			(effects
				(font
					(size 0.7874 0.5842)
					(thickness 0.000001)
				)
				(justify left)
			)
		)
		(duplicate_pad_numbers_are_jumpers no)
		(fp_poly
			(pts
				(arc
					(start 0.889 0)
					(mid -0.889 0)
					(end 0.889 0)
				)
			)
			(stroke
				(width 0)
				(type default)
			)
			(fill no)
			(layer "B.CrtYd")
		)
		(fp_poly
			(pts
				(arc
					(start 0.889 0)
					(mid -0.889 0)
					(end 0.889 0)
				)
			)
			(stroke
				(width 0)
				(type default)
			)
			(fill no)
			(layer "F.CrtYd")
		)
		(pad "1" thru_hole circle
			(at 0 0)
			(size 0.508 0.508)
			(drill 0.254)
			(layers "*.Cu" "*.Mask")
			(remove_unused_layers no)
			(net "FPGA_CFG_INIT_N")
			(clearance 0.1016)
			(padstack
				(mode front_inner_back)
				(layer "Inner"
					(shape circle)
					(size 0.508 0.508)
					(clearance 0.1016)
				)
				(layer "B.Cu"
					(shape circle)
					(size 0.762 0.762)
					(clearance -0.0254)
				)
			)
		)
	)
)
